# S9S_MB_2U (Grand Teton) — schematic parts with pin connectivity, parts 1621–1621 of 6093; source: Cadence DE-HDL packaged netlist (pstxprt.dat, pstxnet.dat, pstchip.dat)

J28  SCONN288_ADR50017P087CC  SCONN288_ADR50017-P087CC IO  pkg DDR288S_1-1VXB  page 109
  1  VIN_BULK0  POWER  = P12V_S3_AUX_CPU1_NVDIMM
  2  RFU0  TRI  = TP_CHF_CPU1_DIMM2_FRU_0
  3  VIN_MGMT  POWER  = P3V3_AUX
  4  HSCL  IN  = I3C_SPD_DDREFGH_CPU1_LVC1_SCL_3
  5  HSDA  BI  = I3C_SPD_DDREFGH_CPU1_LVC1_SDA
  6  VSS0  POWER  = GND
  7  DQ0_A  BI  = M_F_CPU1_SA_DQ<0>
  8  VSS1  POWER  = GND
  9  DQ1_A  BI  = M_F_CPU1_SA_DQ<1>
  10  VSS2  POWER  = GND
  11  DQS0_A_T  BI  = M_F_CPU1_SA_DQS_DP<0>
  12  DQS0_A_C  BI  = M_F_CPU1_SA_DQS_DN<0>
  13  VSS3  POWER  = GND
  14  DQ4_A  BI  = M_F_CPU1_SA_DQ<4>
  15  VSS4  POWER  = GND
  16  DQ5_A  BI  = M_F_CPU1_SA_DQ<5>
  17  VSS5  POWER  = GND
  18  DQ8_A  BI  = M_F_CPU1_SA_DQ<8>
  19  VSS6  POWER  = GND
  20  DQ9_A  BI  = M_F_CPU1_SA_DQ<9>
  21  VSS7  POWER  = GND
  22  DQS1_A_T  BI  = M_F_CPU1_SA_DQS_DP<1>
  23  DQS1_A_C  BI  = M_F_CPU1_SA_DQS_DN<1>
  24  VSS8  POWER  = GND
  25  DQ12_A  BI  = M_F_CPU1_SA_DQ<12>
  26  VSS9  POWER  = GND
  27  DQ13_A  BI  = M_F_CPU1_SA_DQ<13>
  28  VSS10  POWER  = GND
  29  DQ16_A  BI  = M_F_CPU1_SA_DQ<16>
  30  VSS11  POWER  = GND
  31  DQ17_A  BI  = M_F_CPU1_SA_DQ<17>
  32  VSS12  POWER  = GND
  33  DQS2_A_T  BI  = M_F_CPU1_SA_DQS_DP<2>
  34  DQS2_A_C  BI  = M_F_CPU1_SA_DQS_DN<2>
  35  VSS13  POWER  = GND
  36  DQ20_A  BI  = M_F_CPU1_SA_DQ<20>
  37  VSS14  POWER  = GND
  38  DQ21_A  BI  = M_F_CPU1_SA_DQ<21>
  39  VSS15  POWER  = GND
  40  DQ24_A  BI  = M_F_CPU1_SA_DQ<24>
  41  VSS16  POWER  = GND
  42  DQ25_A  BI  = M_F_CPU1_SA_DQ<25>
  43  VSS17  POWER  = GND
  44  DQS3_A_T  BI  = M_F_CPU1_SA_DQS_DP<3>
  45  DQS3_A_C  BI  = M_F_CPU1_SA_DQS_DN<3>
  46  VSS18  POWER  = GND
  47  DQ28_A  BI  = M_F_CPU1_SA_DQ<28>
  48  VSS19  POWER  = GND
  49  DQ29_A  BI  = M_F_CPU1_SA_DQ<29>
  50  VSS20  POWER  = GND
  51  CB0_A  BI  = M_F_CPU1_SA_CB<0>
  52  VSS21  POWER  = GND
  53  CB1_A  BI  = M_F_CPU1_SA_CB<1>
  54  VSS22  POWER  = GND
  55  DQS4_A_T  BI  = M_F_CPU1_SA_DQS_DP<4>
  56  DQS4_A_C  BI  = M_F_CPU1_SA_DQS_DN<4>
  57  VSS23  POWER  = GND
  58  CB4_A  BI  = M_F_CPU1_SA_CB<4>
  59  VSS24  POWER  = GND
  60  CB5_A  BI  = M_F_CPU1_SA_CB<5>
  61  VSS25  POWER  = GND
  62  ALERT_N  OUT  = M_F_CPU1_ALERT_N
  63  VSS26  POWER  = GND
  64  CS0_A_N  IN  = M_F_CPU1_SA_CS_N<2>
  65  VSS27  POWER  = GND
  66  CA0_A  IN  = M_F_CPU1_SA_CA<0>
  67  VSS28  POWER  = GND
  68  CA2_A  IN  = M_F_CPU1_SA_CA<2>
  69  VSS29  POWER  = GND
  70  CA4_A  IN  = M_F_CPU1_SA_CA<4>
  71  VSS30  POWER  = GND
  72  CA6_A  IN  = M_F_CPU1_SA_CA<6>
  73  VSS31  POWER  = GND
  74  PAR_A  IN  = M_F_CPU1_SA_PAR
  75  VSS32  POWER  = GND
  76  CA0_B  IN  = M_F_CPU1_SB_CA<0>
  77  VSS33  POWER  = GND
  78  CA2_B  IN  = M_F_CPU1_SB_CA<2>
  79  VSS34  POWER  = GND
  80  CA4_B  IN  = M_F_CPU1_SB_CA<4>
  81  VSS35  POWER  = GND
  82  CA6_B  IN  = M_F_CPU1_SB_CA<6>
  83  VSS36  POWER  = GND
  84  CS0_B_N  IN  = M_F_CPU1_SB_CS_N<2>
  85  VSS37  POWER  = GND
  86  \lbd||rsp_a_n\  OUT  = M_F_CPU1_SA_RSP<1>
  87  \lbs||rsp_b_n\  OUT  = M_F_CPU1_SB_RSP<1>
  88  VSS38  POWER  = GND
  89  CB4_B  BI  = M_F_CPU1_SB_CB<4>
  90  VSS39  POWER  = GND
  91  CB5_B  BI  = M_F_CPU1_SB_CB<5>
  92  VSS40  POWER  = GND
  93  \dqs9_b_t||tdqs9_b_t||dbi4_b_n\  BI  = M_F_CPU1_SB_DQS_DP<9>
  94  \dqs9_b_c||tdqs9_b_c\  BI  = M_F_CPU1_SB_DQS_DN<9>
  95  VSS41  POWER  = GND
  96  CB0_B  BI  = M_F_CPU1_SB_CB<0>
  97  VSS42  POWER  = GND
  98  CB1_B  BI  = M_F_CPU1_SB_CB<1>
  99  VSS43  POWER  = GND
  100  DQ0_B  BI  = M_F_CPU1_SB_DQ<0>
  101  VSS44  POWER  = GND
  102  DQ1_B  BI  = M_F_CPU1_SB_DQ<1>
  103  VSS45  POWER  = GND
  104  DQS0_B_T  BI  = M_F_CPU1_SB_DQS_DP<0>
  105  DQS0_B_C  BI  = M_F_CPU1_SB_DQS_DN<0>
  106  VSS46  POWER  = GND
  107  DQ4_B  BI  = M_F_CPU1_SB_DQ<4>
  108  VSS47  POWER  = GND
  109  DQ5_B  BI  = M_F_CPU1_SB_DQ<5>
  110  VSS48  POWER  = GND
  111  DQ8_B  BI  = M_F_CPU1_SB_DQ<8>
  112  VSS49  POWER  = GND
  113  DQ9_B  BI  = M_F_CPU1_SB_DQ<9>
  114  VSS50  POWER  = GND
  115  DQS1_B_T  BI  = M_F_CPU1_SB_DQS_DP<1>
  116  DQS1_B_C  BI  = M_F_CPU1_SB_DQS_DN<1>
  117  VSS51  POWER  = GND
  118  DQ12_B  BI  = M_F_CPU1_SB_DQ<12>
  119  VSS52  POWER  = GND
  120  DQ13_B  BI  = M_F_CPU1_SB_DQ<13>
  121  VSS53  POWER  = GND
  122  DQ16_B  BI  = M_F_CPU1_SB_DQ<16>
  123  VSS54  POWER  = GND
  124  DQ17_B  BI  = M_F_CPU1_SB_DQ<17>
  125  VSS55  POWER  = GND
  126  DQS2_B_T  BI  = M_F_CPU1_SB_DQS_DP<2>
  127  DQS2_B_C  BI  = M_F_CPU1_SB_DQS_DN<2>
  128  VSS56  POWER  = GND
  129  DQ20_B  BI  = M_F_CPU1_SB_DQ<20>
  130  VSS57  POWER  = GND
  131  DQ21_B  BI  = M_F_CPU1_SB_DQ<21>
  132  VSS58  POWER  = GND
  133  DQ24_B  BI  = M_F_CPU1_SB_DQ<24>
  134  VSS59  POWER  = GND
  135  DQ25_B  BI  = M_F_CPU1_SB_DQ<25>
  136  VSS60  POWER  = GND
  137  DQS3_B_T  BI  = M_F_CPU1_SB_DQS_DP<3>
  138  DQS3_B_C  BI  = M_F_CPU1_SB_DQS_DN<3>
  139  VSS61  POWER  = GND
  140  DQ28_B  BI  = M_F_CPU1_SB_DQ<28>
  141  VSS62  POWER  = GND
  142  DQ29_B  BI  = M_F_CPU1_SB_DQ<29>
  143  VSS63  POWER  = GND
  144  RFU1  TRI  = TP_CHF_CPU1_DIMM2_FRU_1
  145  VIN_BULK1  POWER  = P12V_S3_AUX_CPU1_NVDIMM
  146  VIN_BULK2  POWER  = P12V_S3_AUX_CPU1_NVDIMM
  147  \pwr_good||fail_n\  BI  = PWRGD_CHF_CPU1_DIMM2
  148  HSA  IN  = PD_CHF_CPU1_DIMM2_SAA
  149  RFU2  TRI  = TP_CHF_CPU1_DIMM2_FRU_2
  150  RFU3  TRI  = TP_CHF_CPU1_DIMM2_FRU_3
  151  VSS64  POWER  = GND
  152  DQ2_A  BI  = M_F_CPU1_SA_DQ<2>
  153  VSS65  POWER  = GND
  154  DQ3_A  BI  = M_F_CPU1_SA_DQ<3>
  155  VSS66  POWER  = GND
  156  \dqs5_a_c||tdqs5_a_c||dqs5_a_t||tdqs5_a_t\  BI  = M_F_CPU1_SA_DQS_DN<5>
  157  \dqs5_a_t||tdqs5_a_t\  BI  = M_F_CPU1_SA_DQS_DP<5>
  158  VSS67  POWER  = GND
  159  DQ6_A  BI  = M_F_CPU1_SA_DQ<6>
  160  VSS68  POWER  = GND
  161  DQ7_A  BI  = M_F_CPU1_SA_DQ<7>
  162  VSS69  POWER  = GND
  163  DQ10_A  BI  = M_F_CPU1_SA_DQ<10>
  164  VSS70  POWER  = GND
  165  DQ11_A  BI  = M_F_CPU1_SA_DQ<11>
  166  VSS71  POWER  = GND
  167  \dqs6_a_c||tdqs6_a_c||dqs6_a_t||tdqs6_a_t\  BI  = M_F_CPU1_SA_DQS_DN<6>
  168  \dqs6_a_t||tdqs6_a_t\  BI  = M_F_CPU1_SA_DQS_DP<6>
  169  VSS72  POWER  = GND
  170  DQ14_A  BI  = M_F_CPU1_SA_DQ<14>
  171  VSS73  POWER  = GND
  172  DQ15_A  BI  = M_F_CPU1_SA_DQ<15>
  173  VSS74  POWER  = GND
  174  DQ18_A  BI  = M_F_CPU1_SA_DQ<18>
  175  VSS75  POWER  = GND
  176  DQ19_A  BI  = M_F_CPU1_SA_DQ<19>
  177  VSS76  POWER  = GND
  178  \dqs7_a_c||tdqs7_a_c\  BI  = M_F_CPU1_SA_DQS_DN<7>
  179  \dqs7_a_t||tdqs7_a_t\  BI  = M_F_CPU1_SA_DQS_DP<7>
  180  VSS77  POWER  = GND
  181  DQ22_A  BI  = M_F_CPU1_SA_DQ<22>
  182  VSS78  POWER  = GND
  183  DQ23_A  BI  = M_F_CPU1_SA_DQ<23>
  184  VSS79  POWER  = GND
  185  DQ26_A  BI  = M_F_CPU1_SA_DQ<26>
  186  VSS80  POWER  = GND
  187  DQ27_A  BI  = M_F_CPU1_SA_DQ<27>
  188  VSS81  POWER  = GND
  189  \dqs8_a_c||tdqs8_a_c\  BI  = M_F_CPU1_SA_DQS_DN<8>
  190  \dqs8_a_t||tdqs8_a_t\  BI  = M_F_CPU1_SA_DQS_DP<8>
  191  VSS82  POWER  = GND
  192  DQ30_A  BI  = M_F_CPU1_SA_DQ<30>
  193  VSS83  POWER  = GND
  194  DQ31_A  BI  = M_F_CPU1_SA_DQ<31>
  195  VSS84  POWER  = GND
  196  CB2_A  BI  = M_F_CPU1_SA_CB<2>
  197  VSS85  POWER  = GND
  198  CB3_A  BI  = M_F_CPU1_SA_CB<3>
  199  VSS86  POWER  = GND
  200  \dqs9_a_c||tdqs9_a_c\  BI  = M_F_CPU1_SA_DQS_DN<9>
  201  \dqs9_a_t||tdqs9_a_t\  BI  = M_F_CPU1_SA_DQS_DP<9>
  202  VSS87  POWER  = GND
  203  CB6_A  BI  = M_F_CPU1_SA_CB<6>
  204  VSS88  POWER  = GND
  205  CB7_A  BI  = M_F_CPU1_SA_CB<7>
  206  VSS89  POWER  = GND
  207  RESET_N  IN  = RST_M_EF_CPU1_FPGA_N
  208  VSS90  POWER  = GND
  209  CS1_A_N  IN  = M_F_CPU1_SA_CS_N<3>
  210  VSS91  POWER  = GND
  211  CA1_A  IN  = M_F_CPU1_SA_CA<1>
  212  VSS92  POWER  = GND
  213  CA3_A  IN  = M_F_CPU1_SA_CA<3>
  214  VSS93  POWER  = GND
  215  CA5_A  IN  = M_F_CPU1_SA_CA<5>
  216  VSS94  POWER  = GND
  217  CK_T  IN  = M_F_CPU1_CLK_DP<1>
  218  CK_C  IN  = M_F_CPU1_CLK_DN<1>
  219  VSS95  POWER  = GND
  220  RFU4  TRI  = TP_CHF_CPU1_DIMM2_FRU_4
  221  CA1_B  IN  = M_F_CPU1_SB_CA<1>
  222  VSS96  POWER  = GND
  223  CA3_B  IN  = M_F_CPU1_SB_CA<3>
  224  VSS97  POWER  = GND
  225  CA5_B  IN  = M_F_CPU1_SB_CA<5>
  226  VSS98  POWER  = GND
  227  PAR_B  IN  = M_F_CPU1_SB_PAR
  228  VSS99  POWER  = GND
  229  CS1_B_N  IN  = M_F_CPU1_SB_CS_N<3>
  230  VSS100  POWER  = GND
  231  RFU5  TRI  = TP_CHF_CPU1_DIMM2_FRU_5
  232  RFU6  TRI  = TP_CHF_CPU1_DIMM2_FRU_6
  233  VSS101  POWER  = GND
  234  CB6_B  BI  = M_F_CPU1_SB_CB<6>
  235  VSS102  POWER  = GND
  236  CB7_B  BI  = M_F_CPU1_SB_CB<7>
  237  VSS103  POWER  = GND
  238  DQS4_B_C  BI  = M_F_CPU1_SB_DQS_DN<4>
  239  DQS4_B_T  BI  = M_F_CPU1_SB_DQS_DP<4>
  240  VSS104  POWER  = GND
  241  CB2_B  BI  = M_F_CPU1_SB_CB<2>
  242  VSS105  POWER  = GND
  243  CB3_B  BI  = M_F_CPU1_SB_CB<3>
  244  VSS106  POWER  = GND
  245  DQ2_B  BI  = M_F_CPU1_SB_DQ<2>
  246  VSS107  POWER  = GND
  247  DQ3_B  BI  = M_F_CPU1_SB_DQ<3>
  248  VSS108  POWER  = GND
  249  \dqs5_b_c||tdqs5_b_c\  BI  = M_F_CPU1_SB_DQS_DN<5>
  250  \dqs5_b_t||tdqs5_b_t\  BI  = M_F_CPU1_SB_DQS_DP<5>
  251  VSS109  POWER  = GND
  252  DQ6_B  BI  = M_F_CPU1_SB_DQ<6>
  253  VSS110  POWER  = GND
  254  DQ7_B  BI  = M_F_CPU1_SB_DQ<7>
  255  VSS111  POWER  = GND
  256  DQ10_B  BI  = M_F_CPU1_SB_DQ<10>
  257  VSS112  POWER  = GND
  258  DQ11_B  BI  = M_F_CPU1_SB_DQ<11>
  259  VSS113  POWER  = GND
  260  \dqs6_b_c||tdqs6_b_c\  BI  = M_F_CPU1_SB_DQS_DN<6>
  261  \dqs6_b_t||tdqs6_b_t\  BI  = M_F_CPU1_SB_DQS_DP<6>
  262  VSS114  POWER  = GND
  263  DQ14_B  BI  = M_F_CPU1_SB_DQ<14>
  264  VSS115  POWER  = GND
  265  DQ15_B  BI  = M_F_CPU1_SB_DQ<15>
  266  VSS116  POWER  = GND
  267  DQ18_B  BI  = M_F_CPU1_SB_DQ<18>
  268  VSS117  POWER  = GND
  269  DQ19_B  BI  = M_F_CPU1_SB_DQ<19>
  270  VSS118  POWER  = GND
  271  \dqs7_b_c||tdqs7_b_c\  BI  = M_F_CPU1_SB_DQS_DN<7>
  272  \dqs7_b_t||tdqs7_b_t\  BI  = M_F_CPU1_SB_DQS_DP<7>
  273  VSS119  POWER  = GND
  274  DQ22_B  BI  = M_F_CPU1_SB_DQ<22>
  275  VSS120  POWER  = GND
  276  DQ23_B  BI  = M_F_CPU1_SB_DQ<23>
  277  VSS121  POWER  = GND
  278  DQ26_B  BI  = M_F_CPU1_SB_DQ<26>
  279  VSS122  POWER  = GND
  280  DQ27_B  BI  = M_F_CPU1_SB_DQ<27>
  281  VSS123  POWER  = GND
  282  \dqs8_b_c||tdqs8_b_c\  BI  = M_F_CPU1_SB_DQS_DN<8>
  283  \dqs8_b_t||tdqs8_b_t\  BI  = M_F_CPU1_SB_DQS_DP<8>
  284  VSS124  POWER  = GND
  285  DQ30_B  BI  = M_F_CPU1_SB_DQ<30>
  286  VSS125  POWER  = GND
  287  DQ31_B  BI  = M_F_CPU1_SB_DQ<31>
  288  VSS126  POWER  = GND
  G1  G1  POWER  = GND
  G2  G2  POWER  = GND
  G3  G3  POWER  = GND
